(kicad_pcb
	(version 20241229)
	(generator "pcbnew")
	(generator_version "9.0")
	(general
		(thickness 1.61)
		(legacy_teardrops no)
	)
	(paper "A3")
	(title_block
		(title "SO-DIMM DDR5 Tester")
		(date "2025-11-26")
		(rev "1.3.0")
		(comment 9 "footprints 324-330 of 627")
	)
	(layers
		(0 "F.Cu" signal)
		(4 "In1.Cu" power)
		(6 "In2.Cu" mixed)
		(8 "In3.Cu" power)
		(10 "In4.Cu" mixed)
		(12 "In5.Cu" power)
		(14 "In6.Cu" mixed)
		(16 "In7.Cu" power)
		(18 "In8.Cu" power)
		(20 "In9.Cu" mixed)
		(22 "In10.Cu" power)
		(2 "B.Cu" signal)
		(9 "F.Adhes" user "F.Adhesive")
		(11 "B.Adhes" user "B.Adhesive")
		(13 "F.Paste" user)
		(15 "B.Paste" user)
		(5 "F.SilkS" user "F.Silkscreen")
		(7 "B.SilkS" user "B.Silkscreen")
		(1 "F.Mask" user)
		(3 "B.Mask" user)
		(17 "Dwgs.User" user "User.Drawings")
		(19 "Cmts.User" user "User.Comments")
		(21 "Eco1.User" user "User.Eco1")
		(23 "Eco2.User" user "User.Eco2")
		(25 "Edge.Cuts" user)
		(27 "Margin" user)
		(31 "F.CrtYd" user "F.Courtyard")
		(29 "B.CrtYd" user "B.Courtyard")
		(35 "F.Fab" user)
		(33 "B.Fab" user)
	)
	(footprint "antmicro-footprints:R_0402_1005Metric"
		(layer "B.Cu")
		(at 101.15 180.95 -90)
		(descr "Resistor SMD 0402")
		(tags "resistor SMD 0402")
		(property "Reference" "R59"
			(at -1.122484 0.772697 90)
			(layer "B.SilkS")
			(hide yes)
			(effects
				(font
					(size 0.7 0.7)
					(thickness 0.15)
				)
				(justify left bottom mirror)
			)
		)
		(property "Value" "R_22R_0402"
			(at -1.011843 -1.772047 90)
			(layer "B.Fab")
			(effects
				(font
					(size 0.7 0.7)
					(thickness 0.15)
				)
				(justify left bottom mirror)
			)
		)
		(property "Datasheet" "https://www.bourns.com/docs/product-datasheets/cr.pdf"
			(at 0 0 270)
			(layer "F.Fab")
			(hide yes)
			(effects
				(font
					(size 1.27 1.27)
					(thickness 0.15)
				)
			)
		)
		(property "Author" "Antmicro"
			(at -79.8 282.1 0)
			(layer "B.Fab")
			(hide yes)
			(effects
				(font
					(size 1 1)
					(thickness 0.15)
				)
				(justify mirror)
			)
		)
		(property "License" "Apache-2.0"
			(at -79.8 282.1 0)
			(layer "B.Fab")
			(hide yes)
			(effects
				(font
					(size 1 1)
					(thickness 0.15)
				)
				(justify mirror)
			)
		)
		(property "MPN" "CR0402-FX-22R0GLF"
			(at -79.8 282.1 0)
			(layer "B.Fab")
			(hide yes)
			(effects
				(font
					(size 1 1)
					(thickness 0.15)
				)
				(justify mirror)
			)
		)
		(property "Manufacturer" "Bourns"
			(at -79.8 282.1 0)
			(layer "B.Fab")
			(hide yes)
			(effects
				(font
					(size 1 1)
					(thickness 0.15)
				)
				(justify mirror)
			)
		)
		(property "Tolerance" "1%"
			(at -79.8 282.1 0)
			(layer "B.Fab")
			(hide yes)
			(effects
				(font
					(size 1 1)
					(thickness 0.15)
				)
				(justify mirror)
			)
		)
		(property "Val" "22R"
			(at -79.8 282.1 0)
			(layer "B.Fab")
			(hide yes)
			(effects
				(font
					(size 1 1)
					(thickness 0.15)
				)
				(justify mirror)
			)
		)
		(sheetname "/Debug FTDI/")
		(sheetfile "debug-ftdi.kicad_sch")
		(attr exclude_from_pos_files exclude_from_bom dnp)
		(fp_rect
			(start -0.93 0.47)
			(end 0.93 -0.47)
			(stroke
				(width 0.05)
				(type solid)
			)
			(fill no)
			(layer "B.CrtYd")
		)
		(fp_rect
			(start -0.5 0.25)
			(end 0.5 -0.25)
			(stroke
				(width 0.15)
				(type solid)
			)
			(fill no)
			(layer "B.Fab")
		)
		(pad "1" smd roundrect
			(at -0.485 0 270)
			(size 0.59 0.64)
			(layers "B.Cu" "B.Mask" "B.Paste")
			(roundrect_rratio 0.25)
			(net 652 "/Debug FTDI/BDBUS3")
			(pintype "passive")
		)
		(pad "2" smd roundrect
			(at 0.485 0 270)
			(size 0.59 0.64)
			(layers "B.Cu" "B.Mask" "B.Paste")
			(roundrect_rratio 0.25)
			(net 653 "/Debug FTDI/AUX.TMS")
			(pintype "passive")
		)
	)
	(footprint "antmicro-footprints:R_0402_1005Metric"
		(layer "B.Cu")
		(at 84.75 171.4)
		(descr "Resistor SMD 0402")
		(tags "resistor SMD 0402")
		(property "Reference" "R83"
			(at -1.122484 0.772697 180)
			(layer "B.SilkS")
			(hide yes)
			(effects
				(font
					(size 0.7 0.7)
					(thickness 0.15)
				)
				(justify left bottom mirror)
			)
		)
		(property "Value" "R_20k_0402"
			(at -1.011843 -1.772047 180)
			(layer "B.Fab")
			(effects
				(font
					(size 0.7 0.7)
					(thickness 0.15)
				)
				(justify left bottom mirror)
			)
		)
		(property "Datasheet" "https://www.bourns.com/docs/product-datasheets/cr.pdf"
			(at 0 0 0)
			(layer "F.Fab")
			(hide yes)
			(effects
				(font
					(size 1.27 1.27)
					(thickness 0.15)
				)
			)
		)
		(property "Author" "Antmicro"
			(at 0 0 0)
			(layer "B.Fab")
			(hide yes)
			(effects
				(font
					(size 1 1)
					(thickness 0.15)
				)
				(justify mirror)
			)
		)
		(property "License" "Apache-2.0"
			(at 0 0 0)
			(layer "B.Fab")
			(hide yes)
			(effects
				(font
					(size 1 1)
					(thickness 0.15)
				)
				(justify mirror)
			)
		)
		(property "MPN" "CR0402-FX-2002GLF"
			(at 0 0 0)
			(layer "B.Fab")
			(hide yes)
			(effects
				(font
					(size 1 1)
					(thickness 0.15)
				)
				(justify mirror)
			)
		)
		(property "Manufacturer" "Bourns"
			(at 0 0 0)
			(layer "B.Fab")
			(hide yes)
			(effects
				(font
					(size 1 1)
					(thickness 0.15)
				)
				(justify mirror)
			)
		)
		(property "Tolerance" "1%"
			(at 0 0 0)
			(layer "B.Fab")
			(hide yes)
			(effects
				(font
					(size 1 1)
					(thickness 0.15)
				)
				(justify mirror)
			)
		)
		(property "Val" "20k"
			(at 0 0 0)
			(layer "B.Fab")
			(hide yes)
			(effects
				(font
					(size 1 1)
					(thickness 0.15)
				)
				(justify mirror)
			)
		)
		(sheetname "/HDMI + SD Card/")
		(sheetfile "hdmi-sd-card.kicad_sch")
		(attr smd)
		(fp_rect
			(start -0.93 0.47)
			(end 0.93 -0.47)
			(stroke
				(width 0.05)
				(type solid)
			)
			(fill no)
			(layer "B.CrtYd")
		)
		(fp_rect
			(start -0.5 0.25)
			(end 0.5 -0.25)
			(stroke
				(width 0.15)
				(type solid)
			)
			(fill no)
			(layer "B.Fab")
		)
		(pad "1" smd roundrect
			(at -0.485 0)
			(size 0.59 0.64)
			(layers "B.Cu" "B.Mask" "B.Paste")
			(roundrect_rratio 0.25)
			(net 200 "+3V3")
			(pintype "passive")
		)
		(pad "2" smd roundrect
			(at 0.485 0)
			(size 0.59 0.64)
			(layers "B.Cu" "B.Mask" "B.Paste")
			(roundrect_rratio 0.25)
			(net 373 "/FPGA bank 16/SD.CLK")
			(pintype "passive")
		)
	)
	(footprint "antmicro-footprints:R_0402_1005Metric"
		(layer "B.Cu")
		(at 84.75 172.4)
		(descr "Resistor SMD 0402")
		(tags "resistor SMD 0402")
		(property "Reference" "R85"
			(at -1.122484 0.772697 180)
			(layer "B.SilkS")
			(hide yes)
			(effects
				(font
					(size 0.7 0.7)
					(thickness 0.15)
				)
				(justify left bottom mirror)
			)
		)
		(property "Value" "R_20k_0402"
			(at -1.011843 -1.772047 180)
			(layer "B.Fab")
			(effects
				(font
					(size 0.7 0.7)
					(thickness 0.15)
				)
				(justify left bottom mirror)
			)
		)
		(property "Datasheet" "https://www.bourns.com/docs/product-datasheets/cr.pdf"
			(at 0 0 0)
			(layer "F.Fab")
			(hide yes)
			(effects
				(font
					(size 1.27 1.27)
					(thickness 0.15)
				)
			)
		)
		(property "Author" "Antmicro"
			(at 0 0 0)
			(layer "B.Fab")
			(hide yes)
			(effects
				(font
					(size 1 1)
					(thickness 0.15)
				)
				(justify mirror)
			)
		)
		(property "License" "Apache-2.0"
			(at 0 0 0)
			(layer "B.Fab")
			(hide yes)
			(effects
				(font
					(size 1 1)
					(thickness 0.15)
				)
				(justify mirror)
			)
		)
		(property "MPN" "CR0402-FX-2002GLF"
			(at 0 0 0)
			(layer "B.Fab")
			(hide yes)
			(effects
				(font
					(size 1 1)
					(thickness 0.15)
				)
				(justify mirror)
			)
		)
		(property "Manufacturer" "Bourns"
			(at 0 0 0)
			(layer "B.Fab")
			(hide yes)
			(effects
				(font
					(size 1 1)
					(thickness 0.15)
				)
				(justify mirror)
			)
		)
		(property "Tolerance" "1%"
			(at 0 0 0)
			(layer "B.Fab")
			(hide yes)
			(effects
				(font
					(size 1 1)
					(thickness 0.15)
				)
				(justify mirror)
			)
		)
		(property "Val" "20k"
			(at 0 0 0)
			(layer "B.Fab")
			(hide yes)
			(effects
				(font
					(size 1 1)
					(thickness 0.15)
				)
				(justify mirror)
			)
		)
		(sheetname "/HDMI + SD Card/")
		(sheetfile "hdmi-sd-card.kicad_sch")
		(attr smd)
		(fp_rect
			(start -0.93 0.47)
			(end 0.93 -0.47)
			(stroke
				(width 0.05)
				(type solid)
			)
			(fill no)
			(layer "B.CrtYd")
		)
		(fp_rect
			(start -0.5 0.25)
			(end 0.5 -0.25)
			(stroke
				(width 0.15)
				(type solid)
			)
			(fill no)
			(layer "B.Fab")
		)
		(pad "1" smd roundrect
			(at -0.485 0)
			(size 0.59 0.64)
			(layers "B.Cu" "B.Mask" "B.Paste")
			(roundrect_rratio 0.25)
			(net 200 "+3V3")
			(pintype "passive")
		)
		(pad "2" smd roundrect
			(at 0.485 0)
			(size 0.59 0.64)
			(layers "B.Cu" "B.Mask" "B.Paste")
			(roundrect_rratio 0.25)
			(net 372 "/FPGA bank 16/SD.CMD")
			(pintype "passive")
		)
	)
	(footprint "antmicro-footprints:R_0402_1005Metric"
		(layer "B.Cu")
		(at 84.75 167.9)
		(descr "Resistor SMD 0402")
		(tags "resistor SMD 0402")
		(property "Reference" "R81"
			(at -1.122484 0.772697 180)
			(layer "B.SilkS")
			(hide yes)
			(effects
				(font
					(size 0.7 0.7)
					(thickness 0.15)
				)
				(justify left bottom mirror)
			)
		)
		(property "Value" "R_20k_0402"
			(at -1.011843 -1.772047 180)
			(layer "B.Fab")
			(effects
				(font
					(size 0.7 0.7)
					(thickness 0.15)
				)
				(justify left bottom mirror)
			)
		)
		(property "Datasheet" "https://www.bourns.com/docs/product-datasheets/cr.pdf"
			(at 0 0 0)
			(layer "F.Fab")
			(hide yes)
			(effects
				(font
					(size 1.27 1.27)
					(thickness 0.15)
				)
			)
		)
		(property "Author" "Antmicro"
			(at 0 0 0)
			(layer "B.Fab")
			(hide yes)
			(effects
				(font
					(size 1 1)
					(thickness 0.15)
				)
				(justify mirror)
			)
		)
		(property "License" "Apache-2.0"
			(at 0 0 0)
			(layer "B.Fab")
			(hide yes)
			(effects
				(font
					(size 1 1)
					(thickness 0.15)
				)
				(justify mirror)
			)
		)
		(property "MPN" "CR0402-FX-2002GLF"
			(at 0 0 0)
			(layer "B.Fab")
			(hide yes)
			(effects
				(font
					(size 1 1)
					(thickness 0.15)
				)
				(justify mirror)
			)
		)
		(property "Manufacturer" "Bourns"
			(at 0 0 0)
			(layer "B.Fab")
			(hide yes)
			(effects
				(font
					(size 1 1)
					(thickness 0.15)
				)
				(justify mirror)
			)
		)
		(property "Tolerance" "1%"
			(at 0 0 0)
			(layer "B.Fab")
			(hide yes)
			(effects
				(font
					(size 1 1)
					(thickness 0.15)
				)
				(justify mirror)
			)
		)
		(property "Val" "20k"
			(at 0 0 0)
			(layer "B.Fab")
			(hide yes)
			(effects
				(font
					(size 1 1)
					(thickness 0.15)
				)
				(justify mirror)
			)
		)
		(sheetname "/HDMI + SD Card/")
		(sheetfile "hdmi-sd-card.kicad_sch")
		(attr smd)
		(fp_rect
			(start -0.93 0.47)
			(end 0.93 -0.47)
			(stroke
				(width 0.05)
				(type solid)
			)
			(fill no)
			(layer "B.CrtYd")
		)
		(fp_rect
			(start -0.5 0.25)
			(end 0.5 -0.25)
			(stroke
				(width 0.15)
				(type solid)
			)
			(fill no)
			(layer "B.Fab")
		)
		(pad "1" smd roundrect
			(at -0.485 0)
			(size 0.59 0.64)
			(layers "B.Cu" "B.Mask" "B.Paste")
			(roundrect_rratio 0.25)
			(net 200 "+3V3")
			(pintype "passive")
		)
		(pad "2" smd roundrect
			(at 0.485 0)
			(size 0.59 0.64)
			(layers "B.Cu" "B.Mask" "B.Paste")
			(roundrect_rratio 0.25)
			(net 594 "/FPGA bank 16/SD.DAT1")
			(pintype "passive")
		)
	)
	(footprint "antmicro-footprints:R_0402_1005Metric"
		(layer "B.Cu")
		(at 84.745499 166.884)
		(descr "Resistor SMD 0402")
		(tags "resistor SMD 0402")
		(property "Reference" "R80"
			(at -1.122484 0.772697 180)
			(layer "B.SilkS")
			(hide yes)
			(effects
				(font
					(size 0.7 0.7)
					(thickness 0.15)
				)
				(justify left bottom mirror)
			)
		)
		(property "Value" "R_20k_0402"
			(at -1.011843 -1.772047 180)
			(layer "B.Fab")
			(effects
				(font
					(size 0.7 0.7)
					(thickness 0.15)
				)
				(justify left bottom mirror)
			)
		)
		(property "Datasheet" "https://www.bourns.com/docs/product-datasheets/cr.pdf"
			(at 0 0 0)
			(layer "F.Fab")
			(hide yes)
			(effects
				(font
					(size 1.27 1.27)
					(thickness 0.15)
				)
			)
		)
		(property "Author" "Antmicro"
			(at 0 0 0)
			(layer "B.Fab")
			(hide yes)
			(effects
				(font
					(size 1 1)
					(thickness 0.15)
				)
				(justify mirror)
			)
		)
		(property "License" "Apache-2.0"
			(at 0 0 0)
			(layer "B.Fab")
			(hide yes)
			(effects
				(font
					(size 1 1)
					(thickness 0.15)
				)
				(justify mirror)
			)
		)
		(property "MPN" "CR0402-FX-2002GLF"
			(at 0 0 0)
			(layer "B.Fab")
			(hide yes)
			(effects
				(font
					(size 1 1)
					(thickness 0.15)
				)
				(justify mirror)
			)
		)
		(property "Manufacturer" "Bourns"
			(at 0 0 0)
			(layer "B.Fab")
			(hide yes)
			(effects
				(font
					(size 1 1)
					(thickness 0.15)
				)
				(justify mirror)
			)
		)
		(property "Tolerance" "1%"
			(at 0 0 0)
			(layer "B.Fab")
			(hide yes)
			(effects
				(font
					(size 1 1)
					(thickness 0.15)
				)
				(justify mirror)
			)
		)
		(property "Val" "20k"
			(at 0 0 0)
			(layer "B.Fab")
			(hide yes)
			(effects
				(font
					(size 1 1)
					(thickness 0.15)
				)
				(justify mirror)
			)
		)
		(sheetname "/HDMI + SD Card/")
		(sheetfile "hdmi-sd-card.kicad_sch")
		(attr smd)
		(fp_rect
			(start -0.93 0.47)
			(end 0.93 -0.47)
			(stroke
				(width 0.05)
				(type solid)
			)
			(fill no)
			(layer "B.CrtYd")
		)
		(fp_rect
			(start -0.5 0.25)
			(end 0.5 -0.25)
			(stroke
				(width 0.15)
				(type solid)
			)
			(fill no)
			(layer "B.Fab")
		)
		(pad "1" smd roundrect
			(at -0.485 0)
			(size 0.59 0.64)
			(layers "B.Cu" "B.Mask" "B.Paste")
			(roundrect_rratio 0.25)
			(net 200 "+3V3")
			(pintype "passive")
		)
		(pad "2" smd roundrect
			(at 0.485 0)
			(size 0.59 0.64)
			(layers "B.Cu" "B.Mask" "B.Paste")
			(roundrect_rratio 0.25)
			(net 669 "/FPGA bank 16/SD.CD")
			(pintype "passive")
		)
	)
	(footprint "antmicro-footprints:R_0402_1005Metric"
		(layer "B.Cu")
		(at 84.76 168.925)
		(descr "Resistor SMD 0402")
		(tags "resistor SMD 0402")
		(property "Reference" "R82"
			(at -1.122484 0.772697 180)
			(layer "B.SilkS")
			(hide yes)
			(effects
				(font
					(size 0.7 0.7)
					(thickness 0.15)
				)
				(justify left bottom mirror)
			)
		)
		(property "Value" "R_20k_0402"
			(at -1.011843 -1.772047 180)
			(layer "B.Fab")
			(effects
				(font
					(size 0.7 0.7)
					(thickness 0.15)
				)
				(justify left bottom mirror)
			)
		)
		(property "Datasheet" "https://www.bourns.com/docs/product-datasheets/cr.pdf"
			(at 0 0 0)
			(layer "F.Fab")
			(hide yes)
			(effects
				(font
					(size 1.27 1.27)
					(thickness 0.15)
				)
			)
		)
		(property "Author" "Antmicro"
			(at 0 0 0)
			(layer "B.Fab")
			(hide yes)
			(effects
				(font
					(size 1 1)
					(thickness 0.15)
				)
				(justify mirror)
			)
		)
		(property "License" "Apache-2.0"
			(at 0 0 0)
			(layer "B.Fab")
			(hide yes)
			(effects
				(font
					(size 1 1)
					(thickness 0.15)
				)
				(justify mirror)
			)
		)
		(property "MPN" "CR0402-FX-2002GLF"
			(at 0 0 0)
			(layer "B.Fab")
			(hide yes)
			(effects
				(font
					(size 1 1)
					(thickness 0.15)
				)
				(justify mirror)
			)
		)
		(property "Manufacturer" "Bourns"
			(at 0 0 0)
			(layer "B.Fab")
			(hide yes)
			(effects
				(font
					(size 1 1)
					(thickness 0.15)
				)
				(justify mirror)
			)
		)
		(property "Tolerance" "1%"
			(at 0 0 0)
			(layer "B.Fab")
			(hide yes)
			(effects
				(font
					(size 1 1)
					(thickness 0.15)
				)
				(justify mirror)
			)
		)
		(property "Val" "20k"
			(at 0 0 0)
			(layer "B.Fab")
			(hide yes)
			(effects
				(font
					(size 1 1)
					(thickness 0.15)
				)
				(justify mirror)
			)
		)
		(sheetname "/HDMI + SD Card/")
		(sheetfile "hdmi-sd-card.kicad_sch")
		(attr smd)
		(fp_rect
			(start -0.93 0.47)
			(end 0.93 -0.47)
			(stroke
				(width 0.05)
				(type solid)
			)
			(fill no)
			(layer "B.CrtYd")
		)
		(fp_rect
			(start -0.5 0.25)
			(end 0.5 -0.25)
			(stroke
				(width 0.15)
				(type solid)
			)
			(fill no)
			(layer "B.Fab")
		)
		(pad "1" smd roundrect
			(at -0.485 0)
			(size 0.59 0.64)
			(layers "B.Cu" "B.Mask" "B.Paste")
			(roundrect_rratio 0.25)
			(net 200 "+3V3")
			(pintype "passive")
		)
		(pad "2" smd roundrect
			(at 0.485 0)
			(size 0.59 0.64)
			(layers "B.Cu" "B.Mask" "B.Paste")
			(roundrect_rratio 0.25)
			(net 374 "/FPGA bank 16/SD.DAT0")
			(pintype "passive")
		)
	)
	(footprint "antmicro-footprints:R_0402_1005Metric"
		(layer "B.Cu")
		(at 84.75 173.4)
		(descr "Resistor SMD 0402")
		(tags "resistor SMD 0402")
		(property "Reference" "R86"
			(at -1.122484 0.772697 180)
			(layer "B.SilkS")
			(hide yes)
			(effects
				(font
					(size 0.7 0.7)
					(thickness 0.15)
				)
				(justify left bottom mirror)
			)
		)
		(property "Value" "R_20k_0402"
			(at -1.011843 -1.772047 180)
			(layer "B.Fab")
			(effects
				(font
					(size 0.7 0.7)
					(thickness 0.15)
				)
				(justify left bottom mirror)
			)
		)
		(property "Datasheet" "https://www.bourns.com/docs/product-datasheets/cr.pdf"
			(at 0 0 0)
			(layer "F.Fab")
			(hide yes)
			(effects
				(font
					(size 1.27 1.27)
					(thickness 0.15)
				)
			)
		)
		(property "Author" "Antmicro"
			(at 0 0 0)
			(layer "B.Fab")
			(hide yes)
			(effects
				(font
					(size 1 1)
					(thickness 0.15)
				)
				(justify mirror)
			)
		)
		(property "License" "Apache-2.0"
			(at 0 0 0)
			(layer "B.Fab")
			(hide yes)
			(effects
				(font
					(size 1 1)
					(thickness 0.15)
				)
				(justify mirror)
			)
		)
		(property "MPN" "CR0402-FX-2002GLF"
			(at 0 0 0)
			(layer "B.Fab")
			(hide yes)
			(effects
				(font
					(size 1 1)
					(thickness 0.15)
				)
				(justify mirror)
			)
		)
		(property "Manufacturer" "Bourns"
			(at 0 0 0)
			(layer "B.Fab")
			(hide yes)
			(effects
				(font
					(size 1 1)
					(thickness 0.15)
				)
				(justify mirror)
			)
		)
		(property "Tolerance" "1%"
			(at 0 0 0)
			(layer "B.Fab")
			(hide yes)
			(effects
				(font
					(size 1 1)
					(thickness 0.15)
				)
				(justify mirror)
			)
		)
		(property "Val" "20k"
			(at 0 0 0)
			(layer "B.Fab")
			(hide yes)
			(effects
				(font
					(size 1 1)
					(thickness 0.15)
				)
				(justify mirror)
			)
		)
		(sheetname "/HDMI + SD Card/")
		(sheetfile "hdmi-sd-card.kicad_sch")
		(attr smd)
		(fp_rect
			(start -0.93 0.47)
			(end 0.93 -0.47)
			(stroke
				(width 0.05)
				(type solid)
			)
			(fill no)
			(layer "B.CrtYd")
		)
		(fp_rect
			(start -0.5 0.25)
			(end 0.5 -0.25)
			(stroke
				(width 0.15)
				(type solid)
			)
			(fill no)
			(layer "B.Fab")
		)
		(pad "1" smd roundrect
			(at -0.485 0)
			(size 0.59 0.64)
			(layers "B.Cu" "B.Mask" "B.Paste")
			(roundrect_rratio 0.25)
			(net 200 "+3V3")
			(pintype "passive")
		)
		(pad "2" smd roundrect
			(at 0.485 0)
			(size 0.59 0.64)
			(layers "B.Cu" "B.Mask" "B.Paste")
			(roundrect_rratio 0.25)
			(net 371 "/FPGA bank 16/SD.DAT3")
			(pintype "passive")
		)
	)
)
